FILE_TYPE=LIBRARY_PARTS;
primitive 'NB682GDZ';
  pin
    'VIN':
      PIN_NUMBER='(1)';
      PINUSE='POWER';
      NO_LOAD_CHECK='Both';
      NO_IO_CHECK='Both';
      NO_ASSERT_CHECK='TRUE';
      NO_DIR_CHECK='TRUE';
      ALLOW_CONNECT='TRUE';
    'PG':
      PIN_NUMBER='(13)';
      OUTPUT_LOAD='(1.0,-1.0)';
    'PGND':
      PIN_NUMBER='(2)';
      PINUSE='POWER';
      NO_LOAD_CHECK='Both';
      NO_IO_CHECK='Both';
      NO_ASSERT_CHECK='TRUE';
      NO_DIR_CHECK='TRUE';
      ALLOW_CONNECT='TRUE';
    'EN':
      PIN_NUMBER='(5)';
      INPUT_LOAD='(-0.01,0.01)';
    'BST':
      PIN_NUMBER='(9)';
      PINUSE='POWER';
      NO_LOAD_CHECK='Both';
      NO_IO_CHECK='Both';
      NO_ASSERT_CHECK='TRUE';
      NO_DIR_CHECK='TRUE';
      ALLOW_CONNECT='TRUE';
    'AGND':
      PIN_NUMBER='(11)';
      PINUSE='POWER';
      NO_LOAD_CHECK='Both';
      NO_IO_CHECK='Both';
      NO_ASSERT_CHECK='TRUE';
      NO_DIR_CHECK='TRUE';
      ALLOW_CONNECT='TRUE';
    'LP#':
      PIN_NUMBER='(6)';
      INPUT_LOAD='(-0.01,0.01)';
    'C1':
      PIN_NUMBER='(3)';
      INPUT_LOAD='(-0.01,0.01)';
    'C0':
      PIN_NUMBER='(4)';
      INPUT_LOAD='(-0.01,0.01)';
    'MODE':
      PIN_NUMBER='(7)';
      INPUT_LOAD='(-0.01,0.01)';
    'VOUT':
      PIN_NUMBER='(12)';
      PINUSE='POWER';
      NO_LOAD_CHECK='Both';
      NO_IO_CHECK='Both';
      NO_ASSERT_CHECK='TRUE';
      NO_DIR_CHECK='TRUE';
      ALLOW_CONNECT='TRUE';
    'SW':
      PIN_NUMBER='(8)';
      PINUSE='POWER';
      NO_LOAD_CHECK='Both';
      NO_IO_CHECK='Both';
      NO_ASSERT_CHECK='TRUE';
      NO_DIR_CHECK='TRUE';
      ALLOW_CONNECT='TRUE';
    '3V3':
      PIN_NUMBER='(10)';
      PINUSE='POWER';
      NO_LOAD_CHECK='Both';
      NO_IO_CHECK='Both';
      NO_ASSERT_CHECK='TRUE';
      NO_DIR_CHECK='TRUE';
      ALLOW_CONNECT='TRUE';
  end_pin;
  body
    PART_NAME='NB682GDZ';
    BODY_NAME='NB682GDZ';
    PHYS_DES_PREFIX='U';
    CLASS='IC';
  end_body;
end_primitive;

END.
